(kicad_pcb
	(version 20260206)
	(generator "pcbnew")
	(generator_version "10.0")
	(general
		(thickness 1.6)
		(legacy_teardrops no)
	)
	(paper "A4")
	(title_block
		(title "panther-plus-userver — 13130-1b_20150205.brd")
		(comment 1 "Honey Badger (Wiwynn) / footprints 1258-1264 of 1509")
	)
	(layers
		(0 "F.Cu" signal "TOP")
		(4 "In1.Cu" signal "L2")
		(6 "In2.Cu" signal "L3")
		(8 "In3.Cu" signal "L4")
		(10 "In4.Cu" signal "L5")
		(12 "In5.Cu" signal "L6")
		(14 "In6.Cu" signal "L7")
		(16 "In7.Cu" signal "L8")
		(18 "In8.Cu" signal "L9")
		(20 "In9.Cu" signal "L10")
		(22 "In10.Cu" signal "L11")
		(2 "B.Cu" signal "BOTTOM")
		(9 "F.Adhes" user "F.Adhesive")
		(11 "B.Adhes" user "B.Adhesive")
		(13 "F.Paste" user "Package Geometry/Pastemask Top")
		(15 "B.Paste" user "Package Geometry/Pastemask Bottom")
		(5 "F.SilkS" user "Ref Des/Silkscreen Top")
		(7 "B.SilkS" user "Ref Des/Silkscreen Bottom")
		(1 "F.Mask" user "Board Geometry/Soldermask Top")
		(3 "B.Mask" user "Board Geometry/Soldermask Bottom")
		(17 "Dwgs.User" user "User.Drawings")
		(19 "Cmts.User" user "User.Comments")
		(21 "Eco1.User" user "User.Eco1")
		(23 "Eco2.User" user "User.Eco2")
		(25 "Edge.Cuts" user "Board Geometry/Outline")
		(27 "Margin" user)
		(31 "F.CrtYd" user "Package Geometry/Place Bound Top")
		(29 "B.CrtYd" user "Package Geometry/Place Bound Bottom")
		(35 "F.Fab" user "Ref Des/Assembly Top")
		(33 "B.Fab" user "Ref Des/Assembly Bottom")
	)
	(footprint ""
		(layer "B.Cu")
		(at 87.4903 -40.4368 90)
		(property "Reference" "R302"
			(at 0 0 90)
			(layer "B.SilkS")
			(hide yes)
			(effects
				(font
					(size 1.27 1.27)
				)
				(justify mirror)
			)
		)
		(property "Value" "0R2J-2-GP"
			(at -0.064008 -3.993896 90)
			(unlocked yes)
			(layer "B.Fab")
			(hide yes)
			(effects
				(font
					(size 1.016 1.016)
					(thickness 0.1524)
				)
				(justify mirror)
			)
		)
		(property "Device Type" "R402H16"
			(at -0.064008 -5.517896 90)
			(unlocked yes)
			(layer "B.Fab")
			(hide yes)
			(effects
				(font
					(size 1.016 1.016)
					(thickness 0.1524)
				)
				(justify mirror)
			)
		)
		(duplicate_pad_numbers_are_jumpers no)
		(fp_rect
			(start 0.381 0.8382)
			(end -0.381 -0.8382)
			(stroke
				(width 0)
				(type default)
			)
			(fill no)
			(layer "B.CrtYd")
		)
		(fp_rect
			(start 0.381 0.8382)
			(end -0.381 -0.8382)
			(stroke
				(width 0)
				(type default)
			)
			(fill no)
			(layer "B.Fab")
		)
		(pad "1" smd custom
			(at 0 -0.4318 270)
			(size 0.127 0.127)
			(layers "B.Cu" "B.Mask" "B.Paste")
			(net "IRQ_MCERR_R#")
			(options
				(clearance outline)
				(anchor circle)
			)
			(primitives
				(gr_poly
					(pts
						(arc
							(start -0.2032 0.2794)
							(mid -0.239121 0.264521)
							(end -0.254 0.2286)
						)
						(arc
							(start -0.254 -0.2286)
							(mid -0.239121 -0.264521)
							(end -0.2032 -0.2794)
						)
						(arc
							(start 0.2032 -0.2794)
							(mid 0.239121 -0.264521)
							(end 0.254 -0.2286)
						)
						(arc
							(start 0.254 0.2286)
							(mid 0.239121 0.264521)
							(end 0.2032 0.2794)
						)
					)
					(width 0)
					(fill yes)
				)
			)
		)
		(pad "2" smd custom
			(at 0 0.4318 270)
			(size 0.127 0.127)
			(layers "B.Cu" "B.Mask" "B.Paste")
			(net "IRQ_MCERR#")
			(options
				(clearance outline)
				(anchor circle)
			)
			(primitives
				(gr_poly
					(pts
						(arc
							(start -0.2032 0.2794)
							(mid -0.239121 0.264521)
							(end -0.254 0.2286)
						)
						(arc
							(start -0.254 -0.2286)
							(mid -0.239121 -0.264521)
							(end -0.2032 -0.2794)
						)
						(arc
							(start 0.2032 -0.2794)
							(mid 0.239121 -0.264521)
							(end 0.254 -0.2286)
						)
						(arc
							(start 0.254 0.2286)
							(mid 0.239121 0.264521)
							(end 0.2032 0.2794)
						)
					)
					(width 0)
					(fill yes)
				)
			)
		)
	)
	(footprint ""
		(layer "B.Cu")
		(at 31.369 -30.734 90)
		(property "Reference" "R273"
			(at 0 0 90)
			(layer "B.SilkS")
			(hide yes)
			(effects
				(font
					(size 1.27 1.27)
				)
				(justify mirror)
			)
		)
		(property "Value" "0R3J-0-U-GP"
			(at 0.0254 -2.5146 90)
			(unlocked yes)
			(layer "B.Fab")
			(hide yes)
			(effects
				(font
					(size 1.016 1.016)
					(thickness 0.1524)
				)
				(justify mirror)
			)
		)
		(property "Device Type" "R603H22"
			(at 0.0254 -4.0386 90)
			(unlocked yes)
			(layer "B.Fab")
			(hide yes)
			(effects
				(font
					(size 1.016 1.016)
					(thickness 0.1524)
				)
				(justify mirror)
			)
		)
		(duplicate_pad_numbers_are_jumpers no)
		(fp_line
			(start 0.2032 0)
			(end 0.4191 0)
			(stroke
				(width 0.2032)
				(type default)
			)
			(layer "B.SilkS")
		)
		(fp_line
			(start -0.4318 0)
			(end -0.2032 0)
			(stroke
				(width 0.2032)
				(type default)
			)
			(layer "B.SilkS")
		)
		(fp_rect
			(start 0.635 1.1811)
			(end -0.635 -1.1811)
			(stroke
				(width 0)
				(type default)
			)
			(fill no)
			(layer "B.CrtYd")
		)
		(fp_rect
			(start 0.635 1.1811)
			(end -0.635 -1.1811)
			(stroke
				(width 0)
				(type default)
			)
			(fill no)
			(layer "B.Fab")
		)
		(pad "1" smd custom
			(at 0 -0.6604 270)
			(size 0.19685 0.19685)
			(layers "B.Cu" "B.Mask" "B.Paste")
			(net "P1V0")
			(options
				(clearance outline)
				(anchor circle)
			)
			(primitives
				(gr_poly
					(pts
						(arc
							(start 0.508 0.2921)
							(mid 0.478242 0.363942)
							(end 0.4064 0.3937)
						)
						(arc
							(start -0.4064 0.3937)
							(mid -0.478242 0.363942)
							(end -0.508 0.2921)
						)
						(arc
							(start -0.508 -0.2921)
							(mid -0.478242 -0.363942)
							(end -0.4064 -0.3937)
						)
						(arc
							(start 0.4064 -0.3937)
							(mid 0.478242 -0.363942)
							(end 0.508 -0.2921)
						)
					)
					(width 0)
					(fill yes)
				)
			)
		)
		(pad "2" smd custom
			(at 0 0.6604 270)
			(size 0.19685 0.19685)
			(layers "B.Cu" "B.Mask" "B.Paste")
			(net "VCC_OBS_CD")
			(options
				(clearance outline)
				(anchor circle)
			)
			(primitives
				(gr_poly
					(pts
						(arc
							(start 0.508 0.2921)
							(mid 0.478242 0.363942)
							(end 0.4064 0.3937)
						)
						(arc
							(start -0.4064 0.3937)
							(mid -0.478242 0.363942)
							(end -0.508 0.2921)
						)
						(arc
							(start -0.508 -0.2921)
							(mid -0.478242 -0.363942)
							(end -0.4064 -0.3937)
						)
						(arc
							(start 0.4064 -0.3937)
							(mid 0.478242 -0.363942)
							(end 0.508 -0.2921)
						)
					)
					(width 0)
					(fill yes)
				)
			)
		)
	)
	(footprint ""
		(layer "B.Cu")
		(at 74.93 -49.149 90)
		(property "Reference" "R313"
			(at 0 0 90)
			(layer "B.SilkS")
			(hide yes)
			(effects
				(font
					(size 1.27 1.27)
				)
				(justify mirror)
			)
		)
		(property "Value" "4K7R2F-GP"
			(at -0.064008 -3.993896 90)
			(unlocked yes)
			(layer "B.Fab")
			(hide yes)
			(effects
				(font
					(size 1.016 1.016)
					(thickness 0.1524)
				)
				(justify mirror)
			)
		)
		(property "Device Type" "R402H16"
			(at -0.064008 -5.517896 90)
			(unlocked yes)
			(layer "B.Fab")
			(hide yes)
			(effects
				(font
					(size 1.016 1.016)
					(thickness 0.1524)
				)
				(justify mirror)
			)
		)
		(duplicate_pad_numbers_are_jumpers no)
		(fp_rect
			(start 0.381 0.8382)
			(end -0.381 -0.8382)
			(stroke
				(width 0)
				(type default)
			)
			(fill no)
			(layer "B.CrtYd")
		)
		(fp_rect
			(start 0.381 0.8382)
			(end -0.381 -0.8382)
			(stroke
				(width 0)
				(type default)
			)
			(fill no)
			(layer "B.Fab")
		)
		(pad "1" smd custom
			(at 0 -0.4318 270)
			(size 0.127 0.127)
			(layers "B.Cu" "B.Mask" "B.Paste")
			(net "P3V3")
			(options
				(clearance outline)
				(anchor circle)
			)
			(primitives
				(gr_poly
					(pts
						(arc
							(start -0.2032 0.2794)
							(mid -0.239121 0.264521)
							(end -0.254 0.2286)
						)
						(arc
							(start -0.254 -0.2286)
							(mid -0.239121 -0.264521)
							(end -0.2032 -0.2794)
						)
						(arc
							(start 0.2032 -0.2794)
							(mid 0.239121 -0.264521)
							(end 0.254 -0.2286)
						)
						(arc
							(start 0.254 0.2286)
							(mid 0.239121 0.264521)
							(end 0.2032 0.2794)
						)
					)
					(width 0)
					(fill yes)
				)
			)
		)
		(pad "2" smd custom
			(at 0 0.4318 270)
			(size 0.127 0.127)
			(layers "B.Cu" "B.Mask" "B.Paste")
			(net "SMBUS_HOST_DATA")
			(options
				(clearance outline)
				(anchor circle)
			)
			(primitives
				(gr_poly
					(pts
						(arc
							(start -0.2032 0.2794)
							(mid -0.239121 0.264521)
							(end -0.254 0.2286)
						)
						(arc
							(start -0.254 -0.2286)
							(mid -0.239121 -0.264521)
							(end -0.2032 -0.2794)
						)
						(arc
							(start 0.2032 -0.2794)
							(mid 0.239121 -0.264521)
							(end 0.254 -0.2286)
						)
						(arc
							(start 0.254 0.2286)
							(mid 0.239121 0.264521)
							(end 0.2032 0.2794)
						)
					)
					(width 0)
					(fill yes)
				)
			)
		)
	)
	(footprint ""
		(layer "B.Cu")
		(at 22.098 -27.94 -90)
		(property "Reference" "PC63"
			(at 0 0 90)
			(layer "B.SilkS")
			(hide yes)
			(effects
				(font
					(size 1.27 1.27)
				)
				(justify mirror)
			)
		)
		(property "Value" "SCD1U16V2KX-3GP"
			(at -1.8923 -1.2065 270)
			(unlocked yes)
			(layer "B.Fab")
			(hide yes)
			(effects
				(font
					(size 1.016 1.016)
					(thickness 0.1524)
				)
				(justify mirror)
			)
		)
		(property "Device Type" "C402H22"
			(at -1.8923 -2.7305 270)
			(unlocked yes)
			(layer "B.Fab")
			(hide yes)
			(effects
				(font
					(size 1.016 1.016)
					(thickness 0.1524)
				)
				(justify mirror)
			)
		)
		(duplicate_pad_numbers_are_jumpers no)
		(fp_rect
			(start 0.381 0.7366)
			(end -0.381 -0.7366)
			(stroke
				(width 0)
				(type default)
			)
			(fill no)
			(layer "B.CrtYd")
		)
		(fp_rect
			(start 0.381 0.7366)
			(end -0.381 -0.7366)
			(stroke
				(width 0)
				(type default)
			)
			(fill no)
			(layer "B.Fab")
		)
		(pad "1" smd custom
			(at 0 -0.4572 90)
			(size 0.1143 0.1143)
			(layers "B.Cu" "B.Mask" "B.Paste")
			(net "P1V0")
			(options
				(clearance outline)
				(anchor circle)
			)
			(primitives
				(gr_poly
					(pts
						(arc
							(start -0.254 0.1778)
							(mid -0.239121 0.213721)
							(end -0.2032 0.2286)
						)
						(arc
							(start 0.2032 0.2286)
							(mid 0.239121 0.213721)
							(end 0.254 0.1778)
						)
						(arc
							(start 0.254 -0.1778)
							(mid 0.239121 -0.213721)
							(end 0.2032 -0.2286)
						)
						(arc
							(start -0.2032 -0.2286)
							(mid -0.239121 -0.213721)
							(end -0.254 -0.1778)
						)
					)
					(width 0)
					(fill yes)
				)
			)
		)
		(pad "2" smd custom
			(at 0 0.4572 90)
			(size 0.1143 0.1143)
			(layers "B.Cu" "B.Mask" "B.Paste")
			(net "P1V0_SW_R")
			(options
				(clearance outline)
				(anchor circle)
			)
			(primitives
				(gr_poly
					(pts
						(arc
							(start -0.254 0.1778)
							(mid -0.239121 0.213721)
							(end -0.2032 0.2286)
						)
						(arc
							(start 0.2032 0.2286)
							(mid 0.239121 0.213721)
							(end 0.254 0.1778)
						)
						(arc
							(start 0.254 -0.1778)
							(mid 0.239121 -0.213721)
							(end 0.2032 -0.2286)
						)
						(arc
							(start -0.2032 -0.2286)
							(mid -0.239121 -0.213721)
							(end -0.254 -0.1778)
						)
					)
					(width 0)
					(fill yes)
				)
			)
		)
	)
	(footprint ""
		(layer "B.Cu")
		(at 116.967 -67.056)
		(property "Reference" "D1"
			(at 0 0 0)
			(layer "B.SilkS")
			(hide yes)
			(effects
				(font
					(size 1.27 1.27)
				)
				(justify mirror)
			)
		)
		(property "Value" "BAT54C-7-F-3-GP"
			(at 3.040634 -3.610864 0)
			(unlocked yes)
			(layer "B.Fab")
			(hide yes)
			(effects
				(font
					(size 1.016 1.016)
					(thickness 0.1524)
				)
				(justify mirror)
			)
		)
		(property "Device Type" "SOT23-2D4-312H48"
			(at 3.040634 -5.134864 0)
			(unlocked yes)
			(layer "B.Fab")
			(hide yes)
			(effects
				(font
					(size 1.016 1.016)
					(thickness 0.1524)
				)
				(justify mirror)
			)
		)
		(duplicate_pad_numbers_are_jumpers no)
		(fp_line
			(start -1.7145 -0.4445)
			(end 1.7145 -0.4445)
			(stroke
				(width 0.1524)
				(type default)
			)
			(layer "B.SilkS")
		)
		(fp_line
			(start -1.7145 0.4445)
			(end -1.7145 -0.4445)
			(stroke
				(width 0.1524)
				(type default)
			)
			(layer "B.SilkS")
		)
		(fp_line
			(start 1.7145 -0.4445)
			(end 1.7145 0.4445)
			(stroke
				(width 0.1524)
				(type default)
			)
			(layer "B.SilkS")
		)
		(fp_line
			(start 1.7145 0.4445)
			(end -1.7145 0.4445)
			(stroke
				(width 0.1524)
				(type default)
			)
			(layer "B.SilkS")
		)
		(fp_poly
			(pts
				(xy 1.4224 1.5621) (xy 1.4224 0.9017) (xy 1.7145 0.9017) (xy 1.7145 -0.9017) (xy 0.4699 -0.9017)
				(xy 0.4699 -1.5621) (xy -0.4699 -1.5621) (xy -0.4699 -0.9017) (xy -1.7145 -0.9017) (xy -1.7145 0.9017)
				(xy -1.4224 0.9017) (xy -1.4224 1.5621) (xy -0.4826 1.5621) (xy -0.4826 0.9017) (xy 0.4826 0.9017)
				(xy 0.4826 1.5621)
			)
			(stroke
				(width 0)
				(type default)
			)
			(fill no)
			(layer "B.CrtYd")
		)
		(fp_poly
			(pts
				(xy 1.4224 1.5621) (xy 1.4224 0.9017) (xy 1.7145 0.9017) (xy 1.7145 -0.9017) (xy 0.4699 -0.9017)
				(xy 0.4699 -1.5621) (xy -0.4699 -1.5621) (xy -0.4699 -0.9017) (xy -1.7145 -0.9017) (xy -1.7145 0.9017)
				(xy -1.4224 0.9017) (xy -1.4224 1.5621) (xy -0.4826 1.5621) (xy -0.4826 0.9017) (xy 0.4826 0.9017)
				(xy 0.4826 1.5621)
			)
			(stroke
				(width 0)
				(type default)
			)
			(fill no)
			(layer "B.Fab")
		)
		(pad "1" smd custom
			(at 0.94996 1.069086 180)
			(size 0.17145 0.17145)
			(layers "B.Cu" "B.Mask" "B.Paste")
			(net "P3V3_STBY")
			(options
				(clearance outline)
				(anchor circle)
			)
			(primitives
				(gr_poly
					(pts
						(arc
							(start -0.1397 -0.3683)
							(mid -0.283384 -0.308784)
							(end -0.3429 -0.1651)
						)
						(arc
							(start -0.3429 0.1651)
							(mid -0.283384 0.308784)
							(end -0.1397 0.3683)
						)
						(arc
							(start 0.1397 0.3683)
							(mid 0.283384 0.308784)
							(end 0.3429 0.1651)
						)
						(arc
							(start 0.3429 -0.1651)
							(mid 0.283384 -0.308784)
							(end 0.1397 -0.3683)
						)
					)
					(width 0)
					(fill yes)
				)
			)
		)
		(pad "2" smd custom
			(at -0.94996 1.069086 180)
			(size 0.17145 0.17145)
			(layers "B.Cu" "B.Mask" "B.Paste")
			(net "P3V0_BAT_R")
			(options
				(clearance outline)
				(anchor circle)
			)
			(primitives
				(gr_poly
					(pts
						(arc
							(start -0.1397 -0.3683)
							(mid -0.283384 -0.308784)
							(end -0.3429 -0.1651)
						)
						(arc
							(start -0.3429 0.1651)
							(mid -0.283384 0.308784)
							(end -0.1397 0.3683)
						)
						(arc
							(start 0.1397 0.3683)
							(mid 0.283384 0.308784)
							(end 0.3429 0.1651)
						)
						(arc
							(start 0.3429 -0.1651)
							(mid 0.283384 -0.308784)
							(end 0.1397 -0.3683)
						)
					)
					(width 0)
					(fill yes)
				)
			)
		)
		(pad "3" smd custom
			(at 0 -1.069086 180)
			(size 0.17145 0.17145)
			(layers "B.Cu" "B.Mask" "B.Paste")
			(net "P3V3_RTC")
			(options
				(clearance outline)
				(anchor circle)
			)
			(primitives
				(gr_poly
					(pts
						(arc
							(start -0.1397 -0.3683)
							(mid -0.283384 -0.308784)
							(end -0.3429 -0.1651)
						)
						(arc
							(start -0.3429 0.1651)
							(mid -0.283384 0.308784)
							(end -0.1397 0.3683)
						)
						(arc
							(start 0.1397 0.3683)
							(mid 0.283384 0.308784)
							(end 0.3429 0.1651)
						)
						(arc
							(start 0.3429 -0.1651)
							(mid 0.283384 -0.308784)
							(end 0.1397 -0.3683)
						)
					)
					(width 0)
					(fill yes)
				)
			)
		)
	)
	(footprint ""
		(layer "B.Cu")
		(at 66.548 -13.589 180)
		(property "Reference" "C305"
			(at 0 0 0)
			(layer "B.SilkS")
			(hide yes)
			(effects
				(font
					(size 1.27 1.27)
				)
				(justify mirror)
			)
		)
		(property "Value" "SCD01U16V2KX-3GP"
			(at -1.8923 -1.2065 180)
			(unlocked yes)
			(layer "B.Fab")
			(hide yes)
			(effects
				(font
					(size 1.016 1.016)
					(thickness 0.1524)
				)
				(justify mirror)
			)
		)
		(property "Device Type" "C402H22"
			(at -1.8923 -2.7305 180)
			(unlocked yes)
			(layer "B.Fab")
			(hide yes)
			(effects
				(font
					(size 1.016 1.016)
					(thickness 0.1524)
				)
				(justify mirror)
			)
		)
		(duplicate_pad_numbers_are_jumpers no)
		(fp_rect
			(start 0.381 0.7366)
			(end -0.381 -0.7366)
			(stroke
				(width 0)
				(type default)
			)
			(fill no)
			(layer "B.CrtYd")
		)
		(fp_rect
			(start 0.381 0.7366)
			(end -0.381 -0.7366)
			(stroke
				(width 0)
				(type default)
			)
			(fill no)
			(layer "B.Fab")
		)
		(pad "1" smd custom
			(at 0 -0.4572)
			(size 0.1143 0.1143)
			(layers "B.Cu" "B.Mask" "B.Paste")
			(net "SATA2_TX_C_DP0")
			(options
				(clearance outline)
				(anchor circle)
			)
			(primitives
				(gr_poly
					(pts
						(arc
							(start -0.254 0.1778)
							(mid -0.239121 0.213721)
							(end -0.2032 0.2286)
						)
						(arc
							(start 0.2032 0.2286)
							(mid 0.239121 0.213721)
							(end 0.254 0.1778)
						)
						(arc
							(start 0.254 -0.1778)
							(mid 0.239121 -0.213721)
							(end 0.2032 -0.2286)
						)
						(arc
							(start -0.2032 -0.2286)
							(mid -0.239121 -0.213721)
							(end -0.254 -0.1778)
						)
					)
					(width 0)
					(fill yes)
				)
			)
		)
		(pad "2" smd custom
			(at 0 0.4572)
			(size 0.1143 0.1143)
			(layers "B.Cu" "B.Mask" "B.Paste")
			(net "SATA2_TX_DP0")
			(options
				(clearance outline)
				(anchor circle)
			)
			(primitives
				(gr_poly
					(pts
						(arc
							(start -0.254 0.1778)
							(mid -0.239121 0.213721)
							(end -0.2032 0.2286)
						)
						(arc
							(start 0.2032 0.2286)
							(mid 0.239121 0.213721)
							(end 0.254 0.1778)
						)
						(arc
							(start 0.254 -0.1778)
							(mid 0.239121 -0.213721)
							(end 0.2032 -0.2286)
						)
						(arc
							(start -0.2032 -0.2286)
							(mid -0.239121 -0.213721)
							(end -0.254 -0.1778)
						)
					)
					(width 0)
					(fill yes)
				)
			)
		)
	)
	(footprint ""
		(layer "B.Cu")
		(at 91.186 -37.4142 180)
		(property "Reference" "C198"
			(at 0 0 0)
			(layer "B.SilkS")
			(hide yes)
			(effects
				(font
					(size 1.27 1.27)
				)
				(justify mirror)
			)
		)
		(property "Value" "SC1U10V2KX-1GP"
			(at -1.1811 -2.7051 180)
			(unlocked yes)
			(layer "B.Fab")
			(hide yes)
			(effects
				(font
					(size 1.016 1.016)
					(thickness 0.1524)
				)
				(justify mirror)
			)
		)
		(property "Device Type" "C402H22"
			(at -1.1811 -4.2291 180)
			(unlocked yes)
			(layer "B.Fab")
			(hide yes)
			(effects
				(font
					(size 1.016 1.016)
					(thickness 0.1524)
				)
				(justify mirror)
			)
		)
		(duplicate_pad_numbers_are_jumpers no)
		(fp_rect
			(start 0.381 0.7366)
			(end -0.381 -0.7366)
			(stroke
				(width 0)
				(type default)
			)
			(fill no)
			(layer "B.CrtYd")
		)
		(fp_rect
			(start 0.381 0.7366)
			(end -0.381 -0.7366)
			(stroke
				(width 0)
				(type default)
			)
			(fill no)
			(layer "B.Fab")
		)
		(pad "1" smd custom
			(at 0 -0.4572)
			(size 0.1143 0.1143)
			(layers "B.Cu" "B.Mask" "B.Paste")
			(net "P3V3_CPU")
			(options
				(clearance outline)
				(anchor circle)
			)
			(primitives
				(gr_poly
					(pts
						(arc
							(start -0.254 0.1778)
							(mid -0.239121 0.213721)
							(end -0.2032 0.2286)
						)
						(arc
							(start 0.2032 0.2286)
							(mid 0.239121 0.213721)
							(end 0.254 0.1778)
						)
						(arc
							(start 0.254 -0.1778)
							(mid 0.239121 -0.213721)
							(end 0.2032 -0.2286)
						)
						(arc
							(start -0.2032 -0.2286)
							(mid -0.239121 -0.213721)
							(end -0.254 -0.1778)
						)
					)
					(width 0)
					(fill yes)
				)
			)
		)
		(pad "2" smd custom
			(at 0 0.4572)
			(size 0.1143 0.1143)
			(layers "B.Cu" "B.Mask" "B.Paste")
			(net "GND")
			(options
				(clearance outline)
				(anchor circle)
			)
			(primitives
				(gr_poly
					(pts
						(arc
							(start -0.254 0.1778)
							(mid -0.239121 0.213721)
							(end -0.2032 0.2286)
						)
						(arc
							(start 0.2032 0.2286)
							(mid 0.239121 0.213721)
							(end 0.254 0.1778)
						)
						(arc
							(start 0.254 -0.1778)
							(mid 0.239121 -0.213721)
							(end 0.2032 -0.2286)
						)
						(arc
							(start -0.2032 -0.2286)
							(mid -0.239121 -0.213721)
							(end -0.254 -0.1778)
						)
					)
					(width 0)
					(fill yes)
				)
			)
		)
	)
)
